(kicad_pcb
	(version 20241229)
	(generator "pcbnew")
	(generator_version "9.0")
	(general
		(thickness 1.61)
		(legacy_teardrops no)
	)
	(paper "A3")
	(title_block
		(title "RDIMM DDR5 Tester")
		(date "2026-05-21")
		(rev "2.2.0")
		(company "Antmicro")
		(comment 9 "footprints 44-47 of 796")
	)
	(layers
		(0 "F.Cu" signal)
		(4 "In1.Cu" power)
		(6 "In2.Cu" mixed)
		(8 "In3.Cu" power)
		(10 "In4.Cu" mixed)
		(12 "In5.Cu" power)
		(14 "In6.Cu" mixed)
		(16 "In7.Cu" power)
		(18 "In8.Cu" power)
		(20 "In9.Cu" mixed)
		(22 "In10.Cu" power)
		(2 "B.Cu" signal)
		(9 "F.Adhes" user "F.Adhesive")
		(11 "B.Adhes" user "B.Adhesive")
		(13 "F.Paste" user)
		(15 "B.Paste" user)
		(5 "F.SilkS" user "F.Silkscreen")
		(7 "B.SilkS" user "B.Silkscreen")
		(1 "F.Mask" user)
		(3 "B.Mask" user)
		(17 "Dwgs.User" user "User.Drawings")
		(19 "Cmts.User" user "User.Comments")
		(21 "Eco1.User" user "User.Eco1")
		(23 "Eco2.User" user "User.Eco2")
		(25 "Edge.Cuts" user)
		(27 "Margin" user)
		(31 "F.CrtYd" user "F.Courtyard")
		(29 "B.CrtYd" user "B.Courtyard")
		(35 "F.Fab" user)
		(33 "B.Fab" user)
	)
	(footprint "antmicro-footprints:SC70-3"
		(layer "F.Cu")
		(at 121.05 115.13269 90)
		(property "Reference" "Q1"
			(at -0.463539 -0.75 180)
			(layer "F.SilkS")
			(effects
				(font
					(size 0.7 0.7)
					(thickness 0.15)
				)
				(justify left bottom)
			)
		)
		(property "Value" "BSS138PW"
			(at 0 2.3 90)
			(layer "F.Fab")
			(effects
				(font
					(size 0.7 0.7)
					(thickness 0.15)
				)
				(justify left bottom)
			)
		)
		(property "Datasheet" "https://assets.nexperia.com/documents/data-sheet/BSS138PW.pdf"
			(at 0 0 90)
			(layer "F.Fab")
			(hide yes)
			(effects
				(font
					(size 1.27 1.27)
					(thickness 0.15)
				)
			)
		)
		(property "MPN" "BSS138PW"
			(at 0 0 90)
			(unlocked yes)
			(layer "F.Fab")
			(hide yes)
			(effects
				(font
					(size 1 1)
					(thickness 0.15)
				)
			)
		)
		(property "Manufacturer" "Nexperia"
			(at 0 0 90)
			(unlocked yes)
			(layer "F.Fab")
			(hide yes)
			(effects
				(font
					(size 1 1)
					(thickness 0.15)
				)
			)
		)
		(property "Author" "Antmicro"
			(at 0 0 90)
			(unlocked yes)
			(layer "F.Fab")
			(hide yes)
			(effects
				(font
					(size 1 1)
					(thickness 0.15)
				)
			)
		)
		(property "License" "Apache-2.0"
			(at 0 0 90)
			(unlocked yes)
			(layer "F.Fab")
			(hide yes)
			(effects
				(font
					(size 1 1)
					(thickness 0.15)
				)
			)
		)
		(sheetname "/FPGA Config/")
		(sheetfile "fpga-config.kicad_sch")
		(attr smd)
		(fp_line
			(start -0.3 -1)
			(end 0.627 -0.999)
			(stroke
				(width 0.15)
				(type solid)
			)
			(layer "F.SilkS")
		)
		(fp_line
			(start 0.627 -0.6)
			(end 0.627 -0.999)
			(stroke
				(width 0.15)
				(type solid)
			)
			(layer "F.SilkS")
		)
		(fp_line
			(start 0.627 0.6)
			(end 0.627 1.001)
			(stroke
				(width 0.15)
				(type solid)
			)
			(layer "F.SilkS")
		)
		(fp_line
			(start -0.3 1)
			(end 0.627 1.001)
			(stroke
				(width 0.15)
				(type solid)
			)
			(layer "F.SilkS")
		)
		(fp_line
			(start 0.9 -1.3)
			(end 0.9 -0.4)
			(stroke
				(width 0.05)
				(type solid)
			)
			(layer "F.CrtYd")
		)
		(fp_line
			(start -0.9 -1.3)
			(end 0.9 -1.3)
			(stroke
				(width 0.05)
				(type solid)
			)
			(layer "F.CrtYd")
		)
		(fp_line
			(start -0.9 -1.3)
			(end -0.9 -1)
			(stroke
				(width 0.05)
				(type solid)
			)
			(layer "F.CrtYd")
		)
		(fp_line
			(start -0.9 -1)
			(end -1.4 -1)
			(stroke
				(width 0.05)
				(type solid)
			)
			(layer "F.CrtYd")
		)
		(fp_line
			(start 1.4 -0.4)
			(end 1.4 0.4)
			(stroke
				(width 0.05)
				(type solid)
			)
			(layer "F.CrtYd")
		)
		(fp_line
			(start 0.9 -0.4)
			(end 1.4 -0.4)
			(stroke
				(width 0.05)
				(type solid)
			)
			(layer "F.CrtYd")
		)
		(fp_line
			(start 1.4 0.4)
			(end 0.9 0.4)
			(stroke
				(width 0.05)
				(type solid)
			)
			(layer "F.CrtYd")
		)
		(fp_line
			(start 0.9 0.4)
			(end 0.9 1.3)
			(stroke
				(width 0.05)
				(type solid)
			)
			(layer "F.CrtYd")
		)
		(fp_line
			(start -0.9 1)
			(end -1.4 1)
			(stroke
				(width 0.05)
				(type solid)
			)
			(layer "F.CrtYd")
		)
		(fp_line
			(start -1.4 1)
			(end -1.4 -1)
			(stroke
				(width 0.05)
				(type solid)
			)
			(layer "F.CrtYd")
		)
		(fp_line
			(start 0.9 1.3)
			(end -0.9 1.3)
			(stroke
				(width 0.05)
				(type solid)
			)
			(layer "F.CrtYd")
		)
		(fp_line
			(start -0.9 1.3)
			(end -0.9 1)
			(stroke
				(width 0.05)
				(type solid)
			)
			(layer "F.CrtYd")
		)
		(fp_rect
			(start -0.623 -0.999)
			(end 0.627 1.001)
			(stroke
				(width 0.15)
				(type solid)
			)
			(fill no)
			(layer "F.Fab")
		)
		(fp_text user "License: Apache-2.0"
			(at -1.45 6.782 90)
			(layer "F.Fab")
			(effects
				(font
					(size 0.7 0.7)
					(thickness 0.15)
				)
				(justify left bottom)
			)
		)
		(fp_text user "Author: Antmicro"
			(at -1.45 5.782 90)
			(layer "F.Fab")
			(effects
				(font
					(size 0.7 0.7)
					(thickness 0.15)
				)
				(justify left bottom)
			)
		)
		(fp_text user "${REFERENCE}"
			(at -1.45 4.783 90)
			(layer "F.Fab")
			(effects
				(font
					(size 0.7 0.7)
					(thickness 0.15)
				)
				(justify left bottom)
			)
		)
		(pad "1" smd rect
			(at -1.051 -0.65 180)
			(size 0.6 0.6)
			(layers "F.Cu" "F.Mask" "F.Paste")
			(net 183 "POWER")
			(pinfunction "G")
			(pintype "passive")
		)
		(pad "2" smd rect
			(at -1.051 0.65 180)
			(size 0.6 0.6)
			(layers "F.Cu" "F.Mask" "F.Paste")
			(net 1 "GND")
			(pinfunction "S")
			(pintype "passive")
		)
		(pad "3" smd rect
			(at 1.05 0 180)
			(size 0.6 0.6)
			(layers "F.Cu" "F.Mask" "F.Paste")
			(net 266 "Net-(Q1-D)")
			(pinfunction "D")
			(pintype "passive")
		)
	)
	(footprint "antmicro-footprints:TP_SMD_1mm"
		(layer "F.Cu")
		(at 244.124499 130.449)
		(property "Reference" "TP16"
			(at 0 -0.731898 0)
			(layer "F.SilkS")
			(hide yes)
			(effects
				(font
					(size 0.7 0.7)
					(thickness 0.15)
				)
				(justify left bottom)
			)
		)
		(property "Value" "TP_1mm_SMD"
			(at 0 1.4 0)
			(layer "F.Fab")
			(effects
				(font
					(size 0.7 0.7)
					(thickness 0.15)
				)
				(justify left bottom)
			)
		)
		(property "MPN" ""
			(at 0 0 0)
			(unlocked yes)
			(layer "F.Fab")
			(hide yes)
			(effects
				(font
					(size 1 1)
					(thickness 0.15)
				)
			)
		)
		(property "Manufacturer" ""
			(at 0 0 0)
			(unlocked yes)
			(layer "F.Fab")
			(hide yes)
			(effects
				(font
					(size 1 1)
					(thickness 0.15)
				)
			)
		)
		(property "Author" "Antmicro"
			(at 0 0 0)
			(unlocked yes)
			(layer "F.Fab")
			(hide yes)
			(effects
				(font
					(size 1 1)
					(thickness 0.15)
				)
			)
		)
		(property "License" "Apache-2.0"
			(at 0 0 0)
			(unlocked yes)
			(layer "F.Fab")
			(hide yes)
			(effects
				(font
					(size 1 1)
					(thickness 0.15)
				)
			)
		)
		(sheetname "/Supply/")
		(sheetfile "supply.kicad_sch")
		(attr exclude_from_pos_files)
		(fp_circle
			(center 0 0)
			(end 0.6 0)
			(stroke
				(width 0.05)
				(type default)
			)
			(fill no)
			(layer "F.CrtYd")
		)
		(fp_text user "License: Apache-2.0"
			(at -0.5 5.2 0)
			(layer "F.Fab")
			(effects
				(font
					(size 0.7 0.7)
					(thickness 0.15)
				)
				(justify left bottom)
			)
		)
		(fp_text user "${REFERENCE}"
			(at -0.5 2.8 0)
			(layer "F.Fab")
			(effects
				(font
					(size 0.7 0.7)
					(thickness 0.15)
				)
				(justify left bottom)
			)
		)
		(fp_text user "Author: Antmicro"
			(at -0.5 4 0)
			(layer "F.Fab")
			(effects
				(font
					(size 0.7 0.7)
					(thickness 0.15)
				)
				(justify left bottom)
			)
		)
		(pad "1" smd circle
			(at 0 0)
			(size 1 1)
			(layers "F.Cu" "F.Mask")
			(net 35 "VDC")
			(pinfunction "1")
			(pintype "passive")
		)
	)
	(footprint "antmicro-footprints:C_0402_1005Metric"
		(layer "F.Cu")
		(at 241.774499 155.3085 90)
		(descr "Capacitor SMD 0402")
		(tags "capacitor SMD 0402")
		(property "Reference" "C206"
			(at 1.1585 0.475501 90)
			(layer "F.SilkS")
			(effects
				(font
					(size 0.7 0.7)
					(thickness 0.15)
				)
				(justify left bottom)
			)
		)
		(property "Value" "C_100n_0402"
			(at -1.022927 2.155213 90)
			(layer "F.Fab")
			(effects
				(font
					(size 0.7 0.7)
					(thickness 0.15)
				)
				(justify left bottom)
			)
		)
		(property "Datasheet" "https://www.murata.com/products/productdetail?partno=GRM155R61H104KE14%23"
			(at 0 0 90)
			(layer "F.Fab")
			(hide yes)
			(effects
				(font
					(size 1.27 1.27)
					(thickness 0.15)
				)
			)
		)
		(property "Manufacturer" "Murata"
			(at 0 0 90)
			(unlocked yes)
			(layer "F.Fab")
			(hide yes)
			(effects
				(font
					(size 1 1)
					(thickness 0.15)
				)
			)
		)
		(property "MPN" "GRM155R61H104KE14D"
			(at 0 0 90)
			(unlocked yes)
			(layer "F.Fab")
			(hide yes)
			(effects
				(font
					(size 1 1)
					(thickness 0.15)
				)
			)
		)
		(property "Val" "100n"
			(at 0 0 90)
			(unlocked yes)
			(layer "F.Fab")
			(hide yes)
			(effects
				(font
					(size 1 1)
					(thickness 0.15)
				)
			)
		)
		(property "License" "Apache-2.0"
			(at 0 0 90)
			(unlocked yes)
			(layer "F.Fab")
			(hide yes)
			(effects
				(font
					(size 1 1)
					(thickness 0.15)
				)
			)
		)
		(property "Author" "Antmicro"
			(at 0 0 90)
			(unlocked yes)
			(layer "F.Fab")
			(hide yes)
			(effects
				(font
					(size 1 1)
					(thickness 0.15)
				)
			)
		)
		(property "Voltage" "50V"
			(at 0 0 90)
			(unlocked yes)
			(layer "F.Fab")
			(hide yes)
			(effects
				(font
					(size 1 1)
					(thickness 0.15)
				)
			)
		)
		(property "Dielectric" "X5R"
			(at 0 0 90)
			(unlocked yes)
			(layer "F.Fab")
			(hide yes)
			(effects
				(font
					(size 1 1)
					(thickness 0.15)
				)
			)
		)
		(sheetname "/Supply/DC-DC IO/")
		(sheetfile "dc-dc-io.kicad_sch")
		(attr smd)
		(fp_rect
			(start -0.925 -0.47)
			(end 0.925 0.47)
			(stroke
				(width 0.05)
				(type default)
			)
			(fill no)
			(layer "F.CrtYd")
		)
		(fp_line
			(start 0.504 -0.25)
			(end 0.504 0.248)
			(stroke
				(width 0.15)
				(type solid)
			)
			(layer "F.Fab")
		)
		(fp_line
			(start -0.494 -0.25)
			(end 0.504 -0.25)
			(stroke
				(width 0.15)
				(type solid)
			)
			(layer "F.Fab")
		)
		(fp_line
			(start 0.504 0.248)
			(end -0.494 0.248)
			(stroke
				(width 0.15)
				(type solid)
			)
			(layer "F.Fab")
		)
		(fp_line
			(start -0.494 0.248)
			(end -0.494 -0.25)
			(stroke
				(width 0.15)
				(type solid)
			)
			(layer "F.Fab")
		)
		(fp_text user "${REFERENCE}"
			(at -0.939 4.599 90)
			(layer "F.Fab")
			(effects
				(font
					(size 0.7 0.7)
					(thickness 0.15)
				)
				(justify left bottom)
			)
		)
		(fp_text user "License: Apache-2.0"
			(at -0.939 5.799 90)
			(layer "F.Fab")
			(effects
				(font
					(size 0.7 0.7)
					(thickness 0.15)
				)
				(justify left bottom)
			)
		)
		(fp_text user "Author: Antmicro"
			(at -0.939 3.399 90)
			(layer "F.Fab")
			(effects
				(font
					(size 0.7 0.7)
					(thickness 0.15)
				)
				(justify left bottom)
			)
		)
		(pad "1" smd roundrect
			(at -0.48 0 90)
			(size 0.59 0.64)
			(layers "F.Cu" "F.Mask" "F.Paste")
			(roundrect_rratio 0.25)
			(net 38 "+3V3_AON")
			(pintype "passive")
		)
		(pad "2" smd roundrect
			(at 0.48 0 90)
			(size 0.59 0.64)
			(layers "F.Cu" "F.Mask" "F.Paste")
			(roundrect_rratio 0.25)
			(net 1 "GND")
			(pintype "passive")
		)
	)
	(footprint "antmicro-footprints:C_Pol_EIA-D"
		(layer "F.Cu")
		(at 221.290002 160.4 90)
		(property "Reference" "C66"
			(at -6 2.434998 90)
			(layer "F.SilkS")
			(effects
				(font
					(size 0.7 0.7)
					(thickness 0.15)
				)
				(justify left bottom)
			)
		)
		(property "Value" "C_Pol_1m_2.5V_KEMET-T520-D"
			(at 0 3.4 90)
			(layer "F.Fab")
			(effects
				(font
					(size 0.7 0.7)
					(thickness 0.15)
				)
				(justify left bottom)
			)
		)
		(property "Datasheet" "https://www.kemet.com/en/us/capacitors/product/T520D108M2R5ATE030.html"
			(at 0 0 90)
			(layer "F.Fab")
			(hide yes)
			(effects
				(font
					(size 1.27 1.27)
					(thickness 0.15)
				)
			)
		)
		(property "MPN" "T520D108M2R5ATE030"
			(at 0 0 90)
			(unlocked yes)
			(layer "F.Fab")
			(hide yes)
			(effects
				(font
					(size 1 1)
					(thickness 0.15)
				)
			)
		)
		(property "Manufacturer" "KEMET"
			(at 0 0 90)
			(unlocked yes)
			(layer "F.Fab")
			(hide yes)
			(effects
				(font
					(size 1 1)
					(thickness 0.15)
				)
			)
		)
		(property "License" "Apache-2.0"
			(at 0 0 90)
			(unlocked yes)
			(layer "F.Fab")
			(hide yes)
			(effects
				(font
					(size 1 1)
					(thickness 0.15)
				)
			)
		)
		(property "Author" "Antmicro"
			(at 0 0 90)
			(unlocked yes)
			(layer "F.Fab")
			(hide yes)
			(effects
				(font
					(size 1 1)
					(thickness 0.15)
				)
			)
		)
		(property "Val" "1000u"
			(at 0 0 90)
			(unlocked yes)
			(layer "F.Fab")
			(hide yes)
			(effects
				(font
					(size 1 1)
					(thickness 0.15)
				)
			)
		)
		(property "Voltage" "2.5V"
			(at 0 0 90)
			(unlocked yes)
			(layer "F.Fab")
			(hide yes)
			(effects
				(font
					(size 1 1)
					(thickness 0.15)
				)
			)
		)
		(property "Dielectric" "template_dielectric"
			(at 0 0 90)
			(unlocked yes)
			(layer "F.Fab")
			(hide yes)
			(effects
				(font
					(size 1 1)
					(thickness 0.15)
				)
			)
		)
		(sheetname "/FPGA power/")
		(sheetfile "fpga-power.kicad_sch")
		(attr smd)
		(fp_line
			(start 3.6 -2.2)
			(end 3.6 -1.6)
			(stroke
				(width 0.15)
				(type solid)
			)
			(layer "F.SilkS")
		)
		(fp_line
			(start -3.58 -2.2)
			(end 3.6 -2.2)
			(stroke
				(width 0.15)
				(type solid)
			)
			(layer "F.SilkS")
		)
		(fp_line
			(start -4.1 -2.025)
			(end -4.1 -1.625)
			(stroke
				(width 0.12)
				(type solid)
			)
			(layer "F.SilkS")
		)
		(fp_line
			(start -4.3 -1.825)
			(end -3.9 -1.825)
			(stroke
				(width 0.12)
				(type solid)
			)
			(layer "F.SilkS")
		)
		(fp_line
			(start -3.58 -1.6)
			(end -3.58 -2.2)
			(stroke
				(width 0.15)
				(type solid)
			)
			(layer "F.SilkS")
		)
		(fp_line
			(start 3.6 1.6)
			(end 3.6 2.2)
			(stroke
				(width 0.15)
				(type solid)
			)
			(layer "F.SilkS")
		)
		(fp_line
			(start 3.6 2.2)
			(end -3.58 2.2)
			(stroke
				(width 0.15)
				(type solid)
			)
			(layer "F.SilkS")
		)
		(fp_line
			(start -3.58 2.2)
			(end -3.58 1.6)
			(stroke
				(width 0.15)
				(type solid)
			)
			(layer "F.SilkS")
		)
		(fp_line
			(start 3.77 -2.4)
			(end 3.77 -1.51)
			(stroke
				(width 0.05)
				(type solid)
			)
			(layer "F.CrtYd")
		)
		(fp_line
			(start -3.775 -2.4)
			(end 3.77 -2.4)
			(stroke
				(width 0.05)
				(type solid)
			)
			(layer "F.CrtYd")
		)
		(fp_line
			(start -3.775 -2.4)
			(end -3.775 -1.5)
			(stroke
				(width 0.05)
				(type solid)
			)
			(layer "F.CrtYd")
		)
		(fp_line
			(start 4.505 -1.51)
			(end 4.505 1.5)
			(stroke
				(width 0.05)
				(type solid)
			)
			(layer "F.CrtYd")
		)
		(fp_line
			(start 3.77 -1.51)
			(end 4.505 -1.51)
			(stroke
				(width 0.05)
				(type solid)
			)
			(layer "F.CrtYd")
		)
		(fp_line
			(start -3.775 -1.5)
			(end -4.505 -1.5)
			(stroke
				(width 0.05)
				(type solid)
			)
			(layer "F.CrtYd")
		)
		(fp_line
			(start 4.505 1.51)
			(end 3.77 1.51)
			(stroke
				(width 0.05)
				(type solid)
			)
			(layer "F.CrtYd")
		)
		(fp_line
			(start 3.77 1.51)
			(end 3.77 2.4)
			(stroke
				(width 0.05)
				(type solid)
			)
			(layer "F.CrtYd")
		)
		(fp_line
			(start -3.77 1.51)
			(end -4.505 1.51)
			(stroke
				(width 0.05)
				(type solid)
			)
			(layer "F.CrtYd")
		)
		(fp_line
			(start -4.505 1.51)
			(end -4.505 -1.5)
			(stroke
				(width 0.05)
				(type solid)
			)
			(layer "F.CrtYd")
		)
		(fp_line
			(start 3.77 2.4)
			(end -3.77 2.4)
			(stroke
				(width 0.05)
				(type solid)
			)
			(layer "F.CrtYd")
		)
		(fp_line
			(start -3.77 2.4)
			(end -3.77 1.51)
			(stroke
				(width 0.05)
				(type solid)
			)
			(layer "F.CrtYd")
		)
		(fp_rect
			(start -3.65 -2.15)
			(end 3.65 2.15)
			(stroke
				(width 0.15)
				(type solid)
			)
			(fill no)
			(layer "F.Fab")
		)
		(fp_text user "Author: Antmicro"
			(at -4.5 7.6 90)
			(layer "F.Fab")
			(effects
				(font
					(size 0.7 0.7)
					(thickness 0.15)
				)
				(justify left bottom)
			)
		)
		(fp_text user "License: Apache-2.0"
			(at -4.5 6.6 90)
			(layer "F.Fab")
			(effects
				(font
					(size 0.7 0.7)
					(thickness 0.15)
				)
				(justify left bottom)
			)
		)
		(fp_text user "${REFERENCE}"
			(at -4.5 5.6 90)
			(layer "F.Fab")
			(effects
				(font
					(size 0.7 0.7)
					(thickness 0.15)
				)
				(justify left bottom)
			)
		)
		(pad "1" smd roundrect
			(at -3.1 0 90)
			(size 2.31 2.52)
			(layers "F.Cu" "F.Mask" "F.Paste")
			(roundrect_rratio 0.1)
			(net 553 "+0V85")
			(pintype "passive")
		)
		(pad "2" smd roundrect
			(at 3.1 0 90)
			(size 2.31 2.52)
			(layers "F.Cu" "F.Mask" "F.Paste")
			(roundrect_rratio 0.1)
			(net 1 "GND")
			(pintype "passive")
		)
	)
)
